(kicad_pcb
	(version 20241229)
	(generator "pcbnew")
	(generator_version "9.0")
	(general
		(thickness 1.711)
		(legacy_teardrops no)
	)
	(paper "A4")
	(title_block
		(title "Antmicro Baseboard for Jetson AGX Thor")
		(date "2026-02-18")
		(rev "1.1.0")
		(company "Antmicro Ltd")
		(comment 1 "www.antmicro.com")
		(comment 9 "footprints 417-421 of 1170")
	)
	(layers
		(0 "F.Cu" signal)
		(4 "In1.Cu" signal)
		(6 "In2.Cu" signal)
		(8 "In3.Cu" signal)
		(10 "In4.Cu" jumper)
		(12 "In5.Cu" signal)
		(14 "In6.Cu" signal)
		(16 "In7.Cu" signal)
		(18 "In8.Cu" signal)
		(2 "B.Cu" signal)
		(9 "F.Adhes" user "F.Adhesive")
		(11 "B.Adhes" user "B.Adhesive")
		(13 "F.Paste" user)
		(15 "B.Paste" user)
		(5 "F.SilkS" user "F.Silkscreen")
		(7 "B.SilkS" user "B.Silkscreen")
		(1 "F.Mask" user)
		(3 "B.Mask" user)
		(17 "Dwgs.User" user "User.Drawings")
		(19 "Cmts.User" user "User.Comments")
		(21 "Eco1.User" user "User.Eco1")
		(23 "Eco2.User" user "User.Eco2")
		(25 "Edge.Cuts" user)
		(27 "Margin" user)
		(31 "F.CrtYd" user "F.Courtyard")
		(29 "B.CrtYd" user "B.Courtyard")
		(35 "F.Fab" user)
		(33 "B.Fab" user)
	)
	(footprint "antmicro-footprints:SOIC-8_3.9x4.9x1.75mm_P1.27mm"
		(layer "F.Cu")
		(at 131 138.002 90)
		(property "Reference" "U2"
			(at 0 -2.85 90)
			(layer "F.SilkS")
			(effects
				(font
					(size 0.7 0.7)
					(thickness 0.15)
				)
				(justify left bottom)
			)
		)
		(property "Value" "AT24CS01_SOIC8"
			(at 0 3.65 90)
			(layer "F.Fab")
			(effects
				(font
					(size 0.7 0.7)
					(thickness 0.15)
				)
				(justify left bottom)
			)
		)
		(property "Datasheet" "https://ww1.microchip.com/downloads/aemDocuments/documents/MPD/ProductDocuments/DataSheets/20006330A.pdf"
			(at 0 0 90)
			(layer "F.Fab")
			(hide yes)
			(effects
				(font
					(size 1.27 1.27)
					(thickness 0.15)
				)
			)
		)
		(property "Description" "EEPROM, 1 Kbit, 128 x 8bit, Serial I2C (2-Wire), 1 MHz, SOIC-8"
			(at 0 0 90)
			(layer "F.Fab")
			(hide yes)
			(effects
				(font
					(size 1.27 1.27)
					(thickness 0.15)
				)
			)
		)
		(property "Manufacturer" "Microchip Technology"
			(at 0 0 90)
			(unlocked yes)
			(layer "F.Fab")
			(hide yes)
			(effects
				(font
					(size 1 1)
					(thickness 0.15)
				)
			)
		)
		(property "MPN" "AT24CS01-SSHM-B"
			(at 0 0 90)
			(unlocked yes)
			(layer "F.Fab")
			(hide yes)
			(effects
				(font
					(size 1 1)
					(thickness 0.15)
				)
			)
		)
		(property "Author" "Antmicro"
			(at 0 0 90)
			(unlocked yes)
			(layer "F.Fab")
			(hide yes)
			(effects
				(font
					(size 1 1)
					(thickness 0.15)
				)
			)
		)
		(property "License" "Apache-2.0"
			(at 0 0 90)
			(unlocked yes)
			(layer "F.Fab")
			(hide yes)
			(effects
				(font
					(size 1 1)
					(thickness 0.15)
				)
			)
		)
		(sheetname "/Expansion connector/")
		(sheetfile "expansion_connector.kicad_sch")
		(attr smd)
		(fp_line
			(start -1.95 -2.452)
			(end 1.95 -2.45)
			(stroke
				(width 0.15)
				(type solid)
			)
			(layer "F.SilkS")
		)
		(fp_line
			(start -1.95 2.45)
			(end 1.95 2.45)
			(stroke
				(width 0.15)
				(type solid)
			)
			(layer "F.SilkS")
		)
		(fp_circle
			(center -2.4 -2.45)
			(end -2.35 -2.4)
			(stroke
				(width 0.15)
				(type solid)
			)
			(fill yes)
			(layer "F.SilkS")
		)
		(fp_rect
			(start -3.625 -2.7)
			(end 3.625 2.7)
			(stroke
				(width 0.05)
				(type solid)
			)
			(fill no)
			(layer "F.CrtYd")
		)
		(fp_line
			(start 1.949 -2.452)
			(end 1.949 2.45)
			(stroke
				(width 0.15)
				(type solid)
			)
			(layer "F.Fab")
		)
		(fp_line
			(start -0.683 -2.452)
			(end 1.949 -2.452)
			(stroke
				(width 0.15)
				(type solid)
			)
			(layer "F.Fab")
		)
		(fp_line
			(start -1.95 -1.18)
			(end -0.683 -2.452)
			(stroke
				(width 0.15)
				(type solid)
			)
			(layer "F.Fab")
		)
		(fp_line
			(start 1.949 2.45)
			(end -1.95 2.45)
			(stroke
				(width 0.15)
				(type solid)
			)
			(layer "F.Fab")
		)
		(fp_line
			(start -1.95 2.45)
			(end -1.95 -1.18)
			(stroke
				(width 0.15)
				(type solid)
			)
			(layer "F.Fab")
		)
		(fp_text user "Author: Antmicro"
			(at -3.476 6.099 90)
			(layer "F.Fab")
			(effects
				(font
					(size 0.7 0.7)
					(thickness 0.15)
				)
				(justify left bottom)
			)
		)
		(fp_text user "License: Apache-2.0"
			(at -3.476 5.099 90)
			(layer "F.Fab")
			(effects
				(font
					(size 0.7 0.7)
					(thickness 0.15)
				)
				(justify left bottom)
			)
		)
		(fp_text user "${REFERENCE}"
			(at -3.476 7.099 90)
			(layer "F.Fab")
			(effects
				(font
					(size 0.7 0.7)
					(thickness 0.15)
				)
				(justify left bottom)
			)
		)
		(pad "1" smd roundrect
			(at -2.714 -1.905 180)
			(size 0.65 1.525)
			(layers "F.Cu" "F.Mask" "F.Paste")
			(roundrect_rratio 0.25)
			(net 677 "/Expansion connector/ADDR0")
			(pinfunction "A0")
			(pintype "input")
		)
		(pad "2" smd roundrect
			(at -2.714 -0.635 180)
			(size 0.65 1.525)
			(layers "F.Cu" "F.Mask" "F.Paste")
			(roundrect_rratio 0.25)
			(net 472 "/Expansion connector/ADDR1")
			(pinfunction "A1")
			(pintype "input")
		)
		(pad "3" smd roundrect
			(at -2.714 0.632 180)
			(size 0.65 1.525)
			(layers "F.Cu" "F.Mask" "F.Paste")
			(roundrect_rratio 0.25)
			(net 1 "GND")
			(pinfunction "A2")
			(pintype "input")
		)
		(pad "4" smd roundrect
			(at -2.714 1.902 180)
			(size 0.65 1.525)
			(layers "F.Cu" "F.Mask" "F.Paste")
			(roundrect_rratio 0.25)
			(net 1 "GND")
			(pinfunction "GND")
			(pintype "power_in")
		)
		(pad "5" smd roundrect
			(at 2.712 1.902 180)
			(size 0.65 1.525)
			(layers "F.Cu" "F.Mask" "F.Paste")
			(roundrect_rratio 0.25)
			(net 561 "/Expansion connector/I2C0.SDA")
			(pinfunction "SDA")
			(pintype "bidirectional")
		)
		(pad "6" smd roundrect
			(at 2.712 0.632 180)
			(size 0.65 1.525)
			(layers "F.Cu" "F.Mask" "F.Paste")
			(roundrect_rratio 0.25)
			(net 407 "/Expansion connector/I2C0.SCL")
			(pinfunction "SCL")
			(pintype "input")
		)
		(pad "7" smd roundrect
			(at 2.712 -0.635 180)
			(size 0.65 1.525)
			(layers "F.Cu" "F.Mask" "F.Paste")
			(roundrect_rratio 0.25)
			(net 1 "GND")
			(pinfunction "WP")
			(pintype "input")
		)
		(pad "8" smd roundrect
			(at 2.712 -1.905 180)
			(size 0.65 1.525)
			(layers "F.Cu" "F.Mask" "F.Paste")
			(roundrect_rratio 0.25)
			(net 148 "/Expansion connector/+3V3_AUX")
			(pinfunction "VCC")
			(pintype "power_in")
		)
	)
	(footprint "antmicro-footprints:R_0402_1005Metric"
		(layer "F.Cu")
		(at 88 61.5 180)
		(descr "Resistor SMD 0402")
		(tags "resistor SMD 0402")
		(property "Reference" "R224"
			(at 16.3 -8.8 0)
			(layer "F.SilkS")
			(effects
				(font
					(size 0.7 0.7)
					(thickness 0.15)
				)
				(justify right top)
			)
		)
		(property "Value" "R_10k_0402"
			(at -1.011843 1.772047 0)
			(layer "F.Fab")
			(effects
				(font
					(size 0.7 0.7)
					(thickness 0.15)
				)
				(justify right top)
			)
		)
		(property "Datasheet" "https://www.bourns.com/docs/product-datasheets/cr.pdf"
			(at 0 0 0)
			(layer "F.Fab")
			(hide yes)
			(effects
				(font
					(size 1.27 1.27)
					(thickness 0.15)
				)
			)
		)
		(property "Description" "SMD Chip Resistor, 10 kohm, ± 1%, 62.5 mW, 0402 [1005 Metric], Thick Film, General Purpose"
			(at 0 0 0)
			(layer "F.Fab")
			(hide yes)
			(effects
				(font
					(size 1.27 1.27)
					(thickness 0.15)
				)
			)
		)
		(property "MPN" "CR0402-FX-1002GLF"
			(at 0 0 180)
			(unlocked yes)
			(layer "F.Fab")
			(hide yes)
			(effects
				(font
					(size 1 1)
					(thickness 0.15)
				)
			)
		)
		(property "Manufacturer" "Bourns"
			(at 0 0 180)
			(unlocked yes)
			(layer "F.Fab")
			(hide yes)
			(effects
				(font
					(size 1 1)
					(thickness 0.15)
				)
			)
		)
		(property "License" "Apache-2.0"
			(at 0 0 180)
			(unlocked yes)
			(layer "F.Fab")
			(hide yes)
			(effects
				(font
					(size 1 1)
					(thickness 0.15)
				)
			)
		)
		(property "Author" "Antmicro"
			(at 0 0 180)
			(unlocked yes)
			(layer "F.Fab")
			(hide yes)
			(effects
				(font
					(size 1 1)
					(thickness 0.15)
				)
			)
		)
		(property "Val" "10k"
			(at 0 0 180)
			(unlocked yes)
			(layer "F.Fab")
			(hide yes)
			(effects
				(font
					(size 1 1)
					(thickness 0.15)
				)
			)
		)
		(property "Tolerance" "1%"
			(at 0 0 180)
			(unlocked yes)
			(layer "F.Fab")
			(hide yes)
			(effects
				(font
					(size 1 1)
					(thickness 0.15)
				)
			)
		)
		(sheetname "/SoM_Power/")
		(sheetfile "som_power.kicad_sch")
		(attr smd)
		(fp_rect
			(start -0.925 -0.47)
			(end 0.925 0.47)
			(stroke
				(width 0.05)
				(type default)
			)
			(fill no)
			(layer "F.CrtYd")
		)
		(fp_rect
			(start -0.5 -0.25)
			(end 0.5 0.25)
			(stroke
				(width 0.15)
				(type solid)
			)
			(fill no)
			(layer "F.Fab")
		)
		(fp_text user "Author: Antmicro"
			(at -0.95 4.169 0)
			(layer "F.Fab")
			(effects
				(font
					(size 0.7 0.7)
					(thickness 0.15)
				)
				(justify right top)
			)
		)
		(fp_text user "License: Apache-2.0"
			(at -0.95 5.169 0)
			(layer "F.Fab")
			(effects
				(font
					(size 0.7 0.7)
					(thickness 0.15)
				)
				(justify right top)
			)
		)
		(fp_text user "${REFERENCE}"
			(at -0.95 3.168 0)
			(layer "F.Fab")
			(effects
				(font
					(size 0.7 0.7)
					(thickness 0.15)
				)
				(justify right top)
			)
		)
		(pad "1" smd roundrect
			(at -0.48 0 180)
			(size 0.59 0.64)
			(layers "F.Cu" "F.Mask" "F.Paste")
			(roundrect_rratio 0.25)
			(net 1027 "Net-(U70-~{CLR})")
			(pintype "passive")
		)
		(pad "2" smd roundrect
			(at 0.48 0 180)
			(size 0.59 0.64)
			(layers "F.Cu" "F.Mask" "F.Paste")
			(roundrect_rratio 0.25)
			(net 213 "+5V_SOM")
			(pintype "passive")
		)
	)
	(footprint "antmicro-footprints:SOD-523"
		(layer "F.Cu")
		(at 112.45 63.45 180)
		(property "Reference" "D55"
			(at -1.07 -0.73 0)
			(layer "F.SilkS")
			(effects
				(font
					(size 0.7 0.7)
					(thickness 0.15)
				)
				(justify right top)
			)
		)
		(property "Value" "PESD5Z5.0F"
			(at 0 1.499 0)
			(layer "F.Fab")
			(effects
				(font
					(size 0.7 0.7)
					(thickness 0.15)
				)
				(justify right top)
			)
		)
		(property "Datasheet" "https://assets.nexperia.com/documents/data-sheet/PESD5Z5_0.pdf"
			(at 0 0 0)
			(layer "F.Fab")
			(hide yes)
			(effects
				(font
					(size 1.27 1.27)
					(thickness 0.15)
				)
			)
		)
		(property "Description" "Unidirectional TVS, 30 kV,  SOD-523, 5 V, 89 pF"
			(at 0 0 0)
			(layer "F.Fab")
			(hide yes)
			(effects
				(font
					(size 1.27 1.27)
					(thickness 0.15)
				)
			)
		)
		(property "Manufacturer" "Nexperia"
			(at 0 0 180)
			(unlocked yes)
			(layer "F.Fab")
			(hide yes)
			(effects
				(font
					(size 1 1)
					(thickness 0.15)
				)
			)
		)
		(property "MPN" "PESD5Z5.0F"
			(at 0 0 180)
			(unlocked yes)
			(layer "F.Fab")
			(hide yes)
			(effects
				(font
					(size 1 1)
					(thickness 0.15)
				)
			)
		)
		(property "Author" "Antmicro"
			(at 0 0 180)
			(unlocked yes)
			(layer "F.Fab")
			(hide yes)
			(effects
				(font
					(size 1 1)
					(thickness 0.15)
				)
			)
		)
		(property "License" "Apache-2.0"
			(at 0 0 180)
			(unlocked yes)
			(layer "F.Fab")
			(hide yes)
			(effects
				(font
					(size 1 1)
					(thickness 0.15)
				)
			)
		)
		(sheetname "/SoM_Power/")
		(sheetfile "som_power.kicad_sch")
		(attr smd)
		(fp_line
			(start -0.35 -0.5)
			(end -0.35 0.5)
			(stroke
				(width 0.15)
				(type solid)
			)
			(layer "F.SilkS")
		)
		(fp_poly
			(pts
				(xy -1 -0.6) (xy 1 -0.6) (xy 1 0.6) (xy -1 0.6)
			)
			(stroke
				(width 0.05)
				(type solid)
			)
			(fill no)
			(layer "F.CrtYd")
		)
		(fp_line
			(start 0.65 -0.425)
			(end 0.65 0.423)
			(stroke
				(width 0.15)
				(type solid)
			)
			(layer "F.Fab")
		)
		(fp_line
			(start -0.35 -0.4)
			(end -0.35 0.4)
			(stroke
				(width 0.15)
				(type solid)
			)
			(layer "F.Fab")
		)
		(fp_line
			(start -0.652 0.423)
			(end 0.65 0.423)
			(stroke
				(width 0.15)
				(type solid)
			)
			(layer "F.Fab")
		)
		(fp_line
			(start -0.652 0.423)
			(end -0.652 -0.425)
			(stroke
				(width 0.15)
				(type solid)
			)
			(layer "F.Fab")
		)
		(fp_line
			(start -0.652 -0.425)
			(end 0.65 -0.425)
			(stroke
				(width 0.15)
				(type solid)
			)
			(layer "F.Fab")
		)
		(fp_text user "${REFERENCE}"
			(at -1.276 3.499 0)
			(layer "F.Fab")
			(effects
				(font
					(size 0.7 0.7)
					(thickness 0.15)
				)
				(justify right top)
			)
		)
		(fp_text user "Author: Antmicro"
			(at -1.276 4.7 0)
			(layer "F.Fab")
			(effects
				(font
					(size 0.7 0.7)
					(thickness 0.15)
				)
				(justify right top)
			)
		)
		(fp_text user "License: Apache-2.0"
			(at -1.276 5.9 0)
			(layer "F.Fab")
			(effects
				(font
					(size 0.7 0.7)
					(thickness 0.15)
				)
				(justify right top)
			)
		)
		(pad "1" smd roundrect
			(at -0.701 0 180)
			(size 0.5 0.6)
			(layers "F.Cu" "F.Mask" "F.Paste")
			(roundrect_rratio 0.25)
			(net 213 "+5V_SOM")
			(pinfunction "C")
			(pintype "passive")
		)
		(pad "2" smd roundrect
			(at 0.699001 0 180)
			(size 0.5 0.6)
			(layers "F.Cu" "F.Mask" "F.Paste")
			(roundrect_rratio 0.25)
			(net 1 "GND")
			(pinfunction "A")
			(pintype "passive")
		)
	)
	(footprint "antmicro-footprints:XDFN-2_1x0.60mm"
		(layer "F.Cu")
		(at 195.25 55.5 -90)
		(property "Reference" "D5"
			(at 0.6 0.55 90)
			(layer "F.SilkS")
			(effects
				(font
					(size 0.7 0.7)
					(thickness 0.15)
				)
				(justify left bottom)
			)
		)
		(property "Value" "TPD1E0B04_XDFN-2"
			(at 0 1.5 90)
			(layer "F.Fab")
			(effects
				(font
					(size 0.7 0.7)
					(thickness 0.15)
				)
				(justify right top)
			)
		)
		(property "Datasheet" "https://www.ti.com/general/docs/suppproductinfo.tsp?distId=26&gotoUrl=https://www.ti.com/lit/gpn/tpd1e0b04"
			(at 0 0 90)
			(layer "F.Fab")
			(hide yes)
			(effects
				(font
					(size 1.27 1.27)
					(thickness 0.15)
				)
			)
		)
		(property "Description" "Bidirectional TVS, 8 kV,  XDFN-2, 3.6 V, 0.18 pF"
			(at 0 0 90)
			(layer "F.Fab")
			(hide yes)
			(effects
				(font
					(size 1.27 1.27)
					(thickness 0.15)
				)
			)
		)
		(property "MPN" "TPD1E0B04DPYR"
			(at 0 0 90)
			(layer "F.Fab")
			(hide yes)
			(effects
				(font
					(size 1.27 1.27)
					(thickness 0.15)
				)
			)
		)
		(property "Manufacturer" "Texas Instruments"
			(at 0 0 90)
			(layer "F.Fab")
			(hide yes)
			(effects
				(font
					(size 1.27 1.27)
					(thickness 0.15)
				)
			)
		)
		(property "Author" "Antmicro"
			(at 0 0 270)
			(unlocked yes)
			(layer "F.Fab")
			(hide yes)
			(effects
				(font
					(size 1 1)
					(thickness 0.15)
				)
			)
		)
		(property "License" "Apache-2.0"
			(at 0 0 270)
			(unlocked yes)
			(layer "F.Fab")
			(hide yes)
			(effects
				(font
					(size 1 1)
					(thickness 0.15)
				)
			)
		)
		(sheetname "/SoM_Power/")
		(sheetfile "som_power.kicad_sch")
		(attr smd)
		(fp_poly
			(pts
				(xy -0.725 -0.475) (xy 0.725 -0.475) (xy 0.725 0.475) (xy -0.725 0.475)
			)
			(stroke
				(width 0.05)
				(type solid)
			)
			(fill no)
			(layer "F.CrtYd")
		)
		(fp_poly
			(pts
				(xy -0.55 -0.35) (xy 0.55 -0.35) (xy 0.55 0.35) (xy -0.55 0.35)
			)
			(stroke
				(width 0.15)
				(type solid)
			)
			(fill no)
			(layer "F.Fab")
		)
		(fp_text user "Author: Antmicro"
			(at -0.8 4.4 90)
			(layer "F.Fab")
			(effects
				(font
					(size 0.7 0.7)
					(thickness 0.15)
				)
				(justify right top)
			)
		)
		(fp_text user "License: Apache-2.0"
			(at -0.799999 5.6 90)
			(layer "F.Fab")
			(effects
				(font
					(size 0.7 0.7)
					(thickness 0.15)
				)
				(justify right top)
			)
		)
		(fp_text user "${REFERENCE}"
			(at -0.8 3.2 90)
			(layer "F.Fab")
			(effects
				(font
					(size 0.7 0.7)
					(thickness 0.15)
				)
				(justify right top)
			)
		)
		(pad "1" smd roundrect
			(at -0.350999 0 270)
			(size 0.3 0.5)
			(layers "F.Cu" "F.Mask" "F.Paste")
			(roundrect_rratio 0.25)
			(net 1 "GND")
			(pinfunction "C")
			(pintype "passive")
		)
		(pad "2" smd roundrect
			(at 0.349 0 270)
			(size 0.3 0.5)
			(layers "F.Cu" "F.Mask" "F.Paste")
			(roundrect_rratio 0.25)
			(net 702 "/SoM_Power/~{SYS_RESET}")
			(pinfunction "A")
			(pintype "passive")
		)
	)
	(footprint "antmicro-footprints:C_0805_2012Metric"
		(layer "F.Cu")
		(at 174.52 142.4 90)
		(descr "Capacitor SMD 0805")
		(tags "capacitor SMD 0805")
		(property "Reference" "C308"
			(at 1.9 0.18 90)
			(layer "F.SilkS")
			(effects
				(font
					(size 0.7 0.7)
					(thickness 0.15)
				)
				(justify left bottom)
			)
		)
		(property "Value" "C_22u_25V_0805"
			(at -2.055717 1.963152 90)
			(layer "F.Fab")
			(effects
				(font
					(size 0.7 0.7)
					(thickness 0.15)
				)
				(justify left bottom)
			)
		)
		(property "Datasheet" "https://product.samsungsem.com/mlcc/CL21A226MAYNNN.do"
			(at 0 0 90)
			(layer "F.Fab")
			(hide yes)
			(effects
				(font
					(size 1.27 1.27)
					(thickness 0.15)
				)
			)
		)
		(property "Description" "SMT Multilayer Ceramic Capacitor, 22uF, +/-20%, 25V, X5R, 0805 [2012 Metric]"
			(at 0 0 90)
			(layer "F.Fab")
			(hide yes)
			(effects
				(font
					(size 1.27 1.27)
					(thickness 0.15)
				)
			)
		)
		(property "Manufacturer" "Samsung Electro-Mechanics"
			(at 0 0 90)
			(unlocked yes)
			(layer "F.Fab")
			(hide yes)
			(effects
				(font
					(size 1 1)
					(thickness 0.15)
				)
			)
		)
		(property "MPN" "CL21A226MAYNNNE"
			(at 0 0 90)
			(unlocked yes)
			(layer "F.Fab")
			(hide yes)
			(effects
				(font
					(size 1 1)
					(thickness 0.15)
				)
			)
		)
		(property "Val" "22u"
			(at 0 0 90)
			(unlocked yes)
			(layer "F.Fab")
			(hide yes)
			(effects
				(font
					(size 1 1)
					(thickness 0.15)
				)
			)
		)
		(property "License" "Apache-2.0"
			(at 0 0 90)
			(unlocked yes)
			(layer "F.Fab")
			(hide yes)
			(effects
				(font
					(size 1 1)
					(thickness 0.15)
				)
			)
		)
		(property "Author" "Antmicro"
			(at 0 0 90)
			(unlocked yes)
			(layer "F.Fab")
			(hide yes)
			(effects
				(font
					(size 1 1)
					(thickness 0.15)
				)
			)
		)
		(property "Voltage" "25V"
			(at 0 0 90)
			(unlocked yes)
			(layer "F.Fab")
			(hide yes)
			(effects
				(font
					(size 1 1)
					(thickness 0.15)
				)
			)
		)
		(property "Dielectric" "X5R"
			(at 0 0 90)
			(unlocked yes)
			(layer "F.Fab")
			(hide yes)
			(effects
				(font
					(size 1 1)
					(thickness 0.15)
				)
			)
		)
		(property "Public" "False"
			(at 0 0 90)
			(unlocked yes)
			(layer "F.Fab")
			(hide yes)
			(effects
				(font
					(size 1 1)
					(thickness 0.15)
				)
			)
		)
		(sheetname "/DCDC/")
		(sheetfile "dcdc.kicad_sch")
		(attr smd)
		(fp_line
			(start -0.3 -0.7)
			(end 0.3 -0.7)
			(stroke
				(width 0.15)
				(type solid)
			)
			(layer "F.SilkS")
		)
		(fp_line
			(start -0.3 0.7)
			(end 0.3 0.7)
			(stroke
				(width 0.15)
				(type solid)
			)
			(layer "F.SilkS")
		)
		(fp_rect
			(start 1.95 -0.9)
			(end -1.95 0.9)
			(stroke
				(width 0.05)
				(type default)
			)
			(fill no)
			(layer "F.CrtYd")
		)
		(fp_rect
			(start -0.95 -0.675)
			(end 0.95 0.675)
			(stroke
				(width 0.15)
				(type solid)
			)
			(fill no)
			(layer "F.Fab")
		)
		(fp_text user "Author: Antmicro"
			(at -1.9 5.947 90)
			(layer "F.Fab")
			(effects
				(font
					(size 0.7 0.7)
					(thickness 0.15)
				)
				(justify left bottom)
			)
		)
		(fp_text user "${REFERENCE}"
			(at -1.9 3.947 90)
			(layer "F.Fab")
			(effects
				(font
					(size 0.7 0.7)
					(thickness 0.15)
				)
				(justify left bottom)
			)
		)
		(fp_text user "License: Apache-2.0"
			(at -1.9 4.947 90)
			(layer "F.Fab")
			(effects
				(font
					(size 0.7 0.7)
					(thickness 0.15)
				)
				(justify left bottom)
			)
		)
		(pad "1" smd roundrect
			(at -1.1 0 90)
			(size 1.2 1.3)
			(layers "F.Cu" "F.Mask" "F.Paste")
			(roundrect_rratio 0.25)
			(net 1 "GND")
			(pintype "passive")
		)
		(pad "2" smd roundrect
			(at 1.1 0 90)
			(size 1.2 1.3)
			(layers "F.Cu" "F.Mask" "F.Paste")
			(roundrect_rratio 0.25)
			(net 13 "VCC")
			(pintype "passive")
		)
	)
)
